(kicad_pcb
	(version 20260206)
	(generator "pcbnew")
	(generator_version "10.0")
	(general
		(thickness 1.6)
		(legacy_teardrops no)
	)
	(paper "A4")
	(title_block
		(title "04192023_DAF0TMB3IC0_F0TG_MB_C_brd_V02_OCP.brd")
		(comment 1 "Grand Teton / footprints 1203-1209 of 8354")
	)
	(layers
		(0 "F.Cu" signal "TOP")
		(4 "In1.Cu" signal "GND")
		(6 "In2.Cu" signal "IN1")
		(8 "In3.Cu" signal "GND1")
		(10 "In4.Cu" signal "IN2")
		(12 "In5.Cu" signal "GND2")
		(14 "In6.Cu" signal "IN3")
		(16 "In7.Cu" signal "GND3")
		(18 "In8.Cu" signal "VCC")
		(20 "In9.Cu" signal "VCC1")
		(22 "In10.Cu" signal "GND4")
		(24 "In11.Cu" signal "IN4")
		(26 "In12.Cu" signal "GND5")
		(28 "In13.Cu" signal "IN5")
		(30 "In14.Cu" signal "GND6")
		(32 "In15.Cu" signal "IN6")
		(34 "In16.Cu" signal "GND7")
		(2 "B.Cu" signal "BOTTOM")
		(9 "F.Adhes" user "F.Adhesive")
		(11 "B.Adhes" user "B.Adhesive")
		(13 "F.Paste" user "Package Geometry/Pastemask Top")
		(15 "B.Paste" user "Package Geometry/Pastemask Bottom")
		(5 "F.SilkS" user "Ref Des/Silkscreen Top")
		(7 "B.SilkS" user "Ref Des/Silkscreen Bottom")
		(1 "F.Mask" user "Board Geometry/Soldermask Top")
		(3 "B.Mask" user "Board Geometry/Soldermask Bottom")
		(17 "Dwgs.User" user "User.Drawings")
		(19 "Cmts.User" user "User.Comments")
		(21 "Eco1.User" user "User.Eco1")
		(23 "Eco2.User" user "User.Eco2")
		(25 "Edge.Cuts" user "Board Geometry/Outline")
		(27 "Margin" user)
		(31 "F.CrtYd" user "Package Geometry/Place Bound Top")
		(29 "B.CrtYd" user "Package Geometry/Place Bound Bottom")
		(35 "F.Fab" user "Ref Des/Assembly Top")
		(33 "B.Fab" user "Ref Des/Assembly Bottom")
	)
	(footprint ""
		(layer "F.Cu")
		(at 426.974 -366.141 -90)
		(property "Reference" "PR125"
			(at 0 0 270)
			(layer "F.SilkS")
			(hide yes)
			(effects
				(font
					(size 1.27 1.27)
				)
			)
		)
		(property "Value" ""
			(at 0 0 270)
			(layer "F.Fab")
			(effects
				(font
					(size 1.27 1.27)
				)
			)
		)
		(duplicate_pad_numbers_are_jumpers no)
		(fp_line
			(start -0.7874 0.4064)
			(end -0.7874 -0.4064)
			(stroke
				(width 0.1524)
				(type default)
			)
			(layer "F.SilkS")
		)
		(fp_line
			(start 0.7874 0.4064)
			(end -0.7874 0.4064)
			(stroke
				(width 0.1524)
				(type default)
			)
			(layer "F.SilkS")
		)
		(fp_line
			(start -0.7874 -0.4064)
			(end 0.7874 -0.4064)
			(stroke
				(width 0.1524)
				(type default)
			)
			(layer "F.SilkS")
		)
		(fp_line
			(start 0.7874 -0.4064)
			(end 0.7874 0.4064)
			(stroke
				(width 0.1524)
				(type default)
			)
			(layer "F.SilkS")
		)
		(fp_line
			(start -0.67945 0.3048)
			(end -0.67945 -0.305054)
			(stroke
				(width 0.1)
				(type default)
			)
			(layer "F.Fab")
		)
		(fp_line
			(start -0.12065 0.3048)
			(end -0.67945 0.3048)
			(stroke
				(width 0.1)
				(type default)
			)
			(layer "F.Fab")
		)
		(fp_line
			(start 0.120396 0.3048)
			(end 0.120396 0.2794)
			(stroke
				(width 0.1)
				(type default)
			)
			(layer "F.Fab")
		)
		(fp_line
			(start 0.67945 0.3048)
			(end 0.120396 0.3048)
			(stroke
				(width 0.1)
				(type default)
			)
			(layer "F.Fab")
		)
		(fp_line
			(start -0.12065 0.2794)
			(end -0.12065 0.3048)
			(stroke
				(width 0.1)
				(type default)
			)
			(layer "F.Fab")
		)
		(fp_line
			(start 0.120396 0.2794)
			(end -0.12065 0.2794)
			(stroke
				(width 0.1)
				(type default)
			)
			(layer "F.Fab")
		)
		(fp_line
			(start -0.12065 -0.2794)
			(end 0.12065 -0.2794)
			(stroke
				(width 0.1)
				(type default)
			)
			(layer "F.Fab")
		)
		(fp_line
			(start 0.12065 -0.2794)
			(end 0.12065 -0.3048)
			(stroke
				(width 0.1)
				(type default)
			)
			(layer "F.Fab")
		)
		(fp_line
			(start 0.12065 -0.3048)
			(end 0.67945 -0.3048)
			(stroke
				(width 0.1)
				(type default)
			)
			(layer "F.Fab")
		)
		(fp_line
			(start 0.67945 -0.3048)
			(end 0.67945 0.3048)
			(stroke
				(width 0.1)
				(type default)
			)
			(layer "F.Fab")
		)
		(fp_line
			(start -0.67945 -0.305054)
			(end -0.12065 -0.305054)
			(stroke
				(width 0.1)
				(type default)
			)
			(layer "F.Fab")
		)
		(fp_line
			(start -0.12065 -0.305054)
			(end -0.12065 -0.2794)
			(stroke
				(width 0.1)
				(type default)
			)
			(layer "F.Fab")
		)
		(pad "1" smd circle
			(at -0.40005 0 270)
			(size 0 0)
			(layers "F.Cu" "F.Mask" "F.Paste")
			(net "P12V_AUX")
		)
		(pad "2" smd circle
			(at 0.40005 0 270)
			(size 0 0)
			(layers "F.Cu" "F.Mask" "F.Paste")
			(net "PVDD11_S3_P0_VINSEN")
		)
	)
	(footprint ""
		(layer "F.Cu")
		(at 337.537044 -383.88163 -90)
		(property "Reference" "C956"
			(at 0 0 270)
			(layer "F.SilkS")
			(hide yes)
			(effects
				(font
					(size 1.27 1.27)
				)
			)
		)
		(property "Value" ""
			(at 0 0 270)
			(layer "F.Fab")
			(effects
				(font
					(size 1.27 1.27)
				)
			)
		)
		(duplicate_pad_numbers_are_jumpers no)
		(fp_line
			(start -0.299974 0.150114)
			(end -0.299974 -0.150114)
			(stroke
				(width 0.1)
				(type default)
			)
			(layer "F.Fab")
		)
		(fp_line
			(start 0.299974 0.150114)
			(end -0.299974 0.150114)
			(stroke
				(width 0.1)
				(type default)
			)
			(layer "F.Fab")
		)
		(fp_line
			(start -0.299974 -0.150114)
			(end 0.299974 -0.150114)
			(stroke
				(width 0.1)
				(type default)
			)
			(layer "F.Fab")
		)
		(fp_line
			(start 0.299974 -0.150114)
			(end 0.299974 0.150114)
			(stroke
				(width 0.1)
				(type default)
			)
			(layer "F.Fab")
		)
		(pad "1" smd rect
			(at -0.2667 0 270)
			(size 0.3048 0.381)
			(layers "F.Cu" "F.Mask" "F.Paste")
			(net "P5E_CPU0_P1_TX_C_DN<4>")
		)
		(pad "2" smd rect
			(at 0.2667 0 270)
			(size 0.3048 0.381)
			(layers "F.Cu" "F.Mask" "F.Paste")
			(net "P5E_CPU0_P1_TX_DN<4>")
		)
	)
	(footprint ""
		(layer "F.Cu")
		(at 192.700148 -430.115726)
		(property "Reference" "R2793"
			(at 0 0 0)
			(layer "F.SilkS")
			(hide yes)
			(effects
				(font
					(size 1.27 1.27)
				)
			)
		)
		(property "Value" ""
			(at 0 0 0)
			(layer "F.Fab")
			(effects
				(font
					(size 1.27 1.27)
				)
			)
		)
		(duplicate_pad_numbers_are_jumpers no)
		(fp_line
			(start -0.7874 -0.4064)
			(end 0.7874 -0.4064)
			(stroke
				(width 0.1524)
				(type default)
			)
			(layer "F.SilkS")
		)
		(fp_line
			(start -0.7874 0.4064)
			(end -0.7874 -0.4064)
			(stroke
				(width 0.1524)
				(type default)
			)
			(layer "F.SilkS")
		)
		(fp_line
			(start 0.7874 -0.4064)
			(end 0.7874 0.4064)
			(stroke
				(width 0.1524)
				(type default)
			)
			(layer "F.SilkS")
		)
		(fp_line
			(start 0.7874 0.4064)
			(end -0.7874 0.4064)
			(stroke
				(width 0.1524)
				(type default)
			)
			(layer "F.SilkS")
		)
		(fp_line
			(start -0.67945 -0.305054)
			(end -0.12065 -0.305054)
			(stroke
				(width 0.1)
				(type default)
			)
			(layer "F.Fab")
		)
		(fp_line
			(start -0.67945 0.3048)
			(end -0.67945 -0.305054)
			(stroke
				(width 0.1)
				(type default)
			)
			(layer "F.Fab")
		)
		(fp_line
			(start -0.12065 -0.305054)
			(end -0.12065 -0.2794)
			(stroke
				(width 0.1)
				(type default)
			)
			(layer "F.Fab")
		)
		(fp_line
			(start -0.12065 -0.2794)
			(end 0.12065 -0.2794)
			(stroke
				(width 0.1)
				(type default)
			)
			(layer "F.Fab")
		)
		(fp_line
			(start -0.12065 0.2794)
			(end -0.12065 0.3048)
			(stroke
				(width 0.1)
				(type default)
			)
			(layer "F.Fab")
		)
		(fp_line
			(start -0.12065 0.3048)
			(end -0.67945 0.3048)
			(stroke
				(width 0.1)
				(type default)
			)
			(layer "F.Fab")
		)
		(fp_line
			(start 0.120396 0.2794)
			(end -0.12065 0.2794)
			(stroke
				(width 0.1)
				(type default)
			)
			(layer "F.Fab")
		)
		(fp_line
			(start 0.120396 0.3048)
			(end 0.120396 0.2794)
			(stroke
				(width 0.1)
				(type default)
			)
			(layer "F.Fab")
		)
		(fp_line
			(start 0.12065 -0.3048)
			(end 0.67945 -0.3048)
			(stroke
				(width 0.1)
				(type default)
			)
			(layer "F.Fab")
		)
		(fp_line
			(start 0.12065 -0.2794)
			(end 0.12065 -0.3048)
			(stroke
				(width 0.1)
				(type default)
			)
			(layer "F.Fab")
		)
		(fp_line
			(start 0.67945 -0.3048)
			(end 0.67945 0.3048)
			(stroke
				(width 0.1)
				(type default)
			)
			(layer "F.Fab")
		)
		(fp_line
			(start 0.67945 0.3048)
			(end 0.120396 0.3048)
			(stroke
				(width 0.1)
				(type default)
			)
			(layer "F.Fab")
		)
		(pad "1" smd circle
			(at -0.40005 0)
			(size 0 0)
			(layers "F.Cu" "F.Mask" "F.Paste")
			(net "FM_PDB_BUF_EN_R_N")
		)
		(pad "2" smd circle
			(at 0.40005 0)
			(size 0 0)
			(layers "F.Cu" "F.Mask" "F.Paste")
			(net "FM_PDB_BUF_EN_R1_N")
		)
	)
	(footprint ""
		(layer "F.Cu")
		(at 124.58827 -34.021268 180)
		(property "Reference" "C6022"
			(at 0 0 180)
			(layer "F.SilkS")
			(hide yes)
			(effects
				(font
					(size 1.27 1.27)
				)
			)
		)
		(property "Value" ""
			(at 0 0 180)
			(layer "F.Fab")
			(effects
				(font
					(size 1.27 1.27)
				)
			)
		)
		(duplicate_pad_numbers_are_jumpers no)
		(fp_line
			(start 0.40005 0.4064)
			(end -0.40005 0.4064)
			(stroke
				(width 0.1524)
				(type default)
			)
			(layer "F.SilkS")
		)
		(fp_line
			(start -0.40005 -0.4064)
			(end 0.40005 -0.4064)
			(stroke
				(width 0.1524)
				(type default)
			)
			(layer "F.SilkS")
		)
		(fp_line
			(start 0.6858 0.3048)
			(end 0.1016 0.3048)
			(stroke
				(width 0.1)
				(type default)
			)
			(layer "F.Fab")
		)
		(fp_line
			(start 0.6858 -0.3048)
			(end 0.6858 0.3048)
			(stroke
				(width 0.1)
				(type default)
			)
			(layer "F.Fab")
		)
		(fp_line
			(start 0.1016 0.3048)
			(end 0.1016 0.2794)
			(stroke
				(width 0.1)
				(type default)
			)
			(layer "F.Fab")
		)
		(fp_line
			(start 0.1016 0.2794)
			(end -0.1016 0.2794)
			(stroke
				(width 0.1)
				(type default)
			)
			(layer "F.Fab")
		)
		(fp_line
			(start 0.1016 -0.2794)
			(end 0.1016 -0.3048)
			(stroke
				(width 0.1)
				(type default)
			)
			(layer "F.Fab")
		)
		(fp_line
			(start 0.1016 -0.3048)
			(end 0.6858 -0.3048)
			(stroke
				(width 0.1)
				(type default)
			)
			(layer "F.Fab")
		)
		(fp_line
			(start -0.1016 0.3048)
			(end -0.6858 0.3048)
			(stroke
				(width 0.1)
				(type default)
			)
			(layer "F.Fab")
		)
		(fp_line
			(start -0.1016 0.2794)
			(end -0.1016 0.3048)
			(stroke
				(width 0.1)
				(type default)
			)
			(layer "F.Fab")
		)
		(fp_line
			(start -0.1016 -0.2794)
			(end 0.1016 -0.2794)
			(stroke
				(width 0.1)
				(type default)
			)
			(layer "F.Fab")
		)
		(fp_line
			(start -0.1016 -0.3048)
			(end -0.1016 -0.2794)
			(stroke
				(width 0.1)
				(type default)
			)
			(layer "F.Fab")
		)
		(fp_line
			(start -0.6858 0.3048)
			(end -0.6858 -0.3048)
			(stroke
				(width 0.1)
				(type default)
			)
			(layer "F.Fab")
		)
		(fp_line
			(start -0.6858 -0.3048)
			(end -0.1016 -0.3048)
			(stroke
				(width 0.1)
				(type default)
			)
			(layer "F.Fab")
		)
		(pad "1" smd rect
			(at -0.40005 0)
			(size 0.4572 0.508)
			(layers "F.Cu" "F.Mask" "F.Paste")
			(net "USB3_CPU0_BMC_RX_DN")
		)
		(pad "2" smd rect
			(at 0.40005 0)
			(size 0.4572 0.508)
			(layers "F.Cu" "F.Mask" "F.Paste")
			(net "USB3_CPU0_BMC_RX_C2_DN")
		)
	)
	(footprint ""
		(layer "F.Cu")
		(at 136.59358 -386.44068 90)
		(property "Reference" "C435"
			(at 0 0 90)
			(layer "F.SilkS")
			(hide yes)
			(effects
				(font
					(size 1.27 1.27)
				)
			)
		)
		(property "Value" ""
			(at 0 0 90)
			(layer "F.Fab")
			(effects
				(font
					(size 1.27 1.27)
				)
			)
		)
		(duplicate_pad_numbers_are_jumpers no)
		(fp_line
			(start 0.7874 -0.4064)
			(end 0.7874 0.4064)
			(stroke
				(width 0.1524)
				(type default)
			)
			(layer "F.SilkS")
		)
		(fp_line
			(start -0.7874 -0.4064)
			(end 0.7874 -0.4064)
			(stroke
				(width 0.1524)
				(type default)
			)
			(layer "F.SilkS")
		)
		(fp_line
			(start 0.7874 0.4064)
			(end -0.7874 0.4064)
			(stroke
				(width 0.1524)
				(type default)
			)
			(layer "F.SilkS")
		)
		(fp_line
			(start -0.7874 0.4064)
			(end -0.7874 -0.4064)
			(stroke
				(width 0.1524)
				(type default)
			)
			(layer "F.SilkS")
		)
		(fp_line
			(start -0.12065 -0.305054)
			(end -0.12065 -0.2794)
			(stroke
				(width 0.1)
				(type default)
			)
			(layer "F.Fab")
		)
		(fp_line
			(start -0.67945 -0.305054)
			(end -0.12065 -0.305054)
			(stroke
				(width 0.1)
				(type default)
			)
			(layer "F.Fab")
		)
		(fp_line
			(start 0.67945 -0.3048)
			(end 0.67945 0.3048)
			(stroke
				(width 0.1)
				(type default)
			)
			(layer "F.Fab")
		)
		(fp_line
			(start 0.12065 -0.3048)
			(end 0.67945 -0.3048)
			(stroke
				(width 0.1)
				(type default)
			)
			(layer "F.Fab")
		)
		(fp_line
			(start 0.12065 -0.2794)
			(end 0.12065 -0.3048)
			(stroke
				(width 0.1)
				(type default)
			)
			(layer "F.Fab")
		)
		(fp_line
			(start -0.12065 -0.2794)
			(end 0.12065 -0.2794)
			(stroke
				(width 0.1)
				(type default)
			)
			(layer "F.Fab")
		)
		(fp_line
			(start 0.120396 0.2794)
			(end -0.12065 0.2794)
			(stroke
				(width 0.1)
				(type default)
			)
			(layer "F.Fab")
		)
		(fp_line
			(start -0.12065 0.2794)
			(end -0.12065 0.3048)
			(stroke
				(width 0.1)
				(type default)
			)
			(layer "F.Fab")
		)
		(fp_line
			(start 0.67945 0.3048)
			(end 0.120396 0.3048)
			(stroke
				(width 0.1)
				(type default)
			)
			(layer "F.Fab")
		)
		(fp_line
			(start 0.120396 0.3048)
			(end 0.120396 0.2794)
			(stroke
				(width 0.1)
				(type default)
			)
			(layer "F.Fab")
		)
		(fp_line
			(start -0.12065 0.3048)
			(end -0.67945 0.3048)
			(stroke
				(width 0.1)
				(type default)
			)
			(layer "F.Fab")
		)
		(fp_line
			(start -0.67945 0.3048)
			(end -0.67945 -0.305054)
			(stroke
				(width 0.1)
				(type default)
			)
			(layer "F.Fab")
		)
		(pad "1" smd circle
			(at -0.40005 0 90)
			(size 0 0)
			(layers "F.Cu" "F.Mask" "F.Paste")
			(net "P1V8_CPU1_RT3_1A")
		)
		(pad "2" smd circle
			(at 0.40005 0 90)
			(size 0 0)
			(layers "F.Cu" "F.Mask" "F.Paste")
			(net "GND")
		)
	)
	(footprint ""
		(layer "F.Cu")
		(at 157.88259 -98.755708 90)
		(property "Reference" "R3303"
			(at 0 0 90)
			(layer "F.SilkS")
			(hide yes)
			(effects
				(font
					(size 1.27 1.27)
				)
			)
		)
		(property "Value" ""
			(at 0 0 90)
			(layer "F.Fab")
			(effects
				(font
					(size 1.27 1.27)
				)
			)
		)
		(duplicate_pad_numbers_are_jumpers no)
		(fp_line
			(start 0.7874 -0.4064)
			(end 0.7874 0.4064)
			(stroke
				(width 0.1524)
				(type default)
			)
			(layer "F.SilkS")
		)
		(fp_line
			(start -0.7874 -0.4064)
			(end 0.7874 -0.4064)
			(stroke
				(width 0.1524)
				(type default)
			)
			(layer "F.SilkS")
		)
		(fp_line
			(start 0.7874 0.4064)
			(end -0.7874 0.4064)
			(stroke
				(width 0.1524)
				(type default)
			)
			(layer "F.SilkS")
		)
		(fp_line
			(start -0.7874 0.4064)
			(end -0.7874 -0.4064)
			(stroke
				(width 0.1524)
				(type default)
			)
			(layer "F.SilkS")
		)
		(fp_line
			(start -0.12065 -0.305054)
			(end -0.12065 -0.2794)
			(stroke
				(width 0.1)
				(type default)
			)
			(layer "F.Fab")
		)
		(fp_line
			(start -0.67945 -0.305054)
			(end -0.12065 -0.305054)
			(stroke
				(width 0.1)
				(type default)
			)
			(layer "F.Fab")
		)
		(fp_line
			(start 0.67945 -0.3048)
			(end 0.67945 0.3048)
			(stroke
				(width 0.1)
				(type default)
			)
			(layer "F.Fab")
		)
		(fp_line
			(start 0.12065 -0.3048)
			(end 0.67945 -0.3048)
			(stroke
				(width 0.1)
				(type default)
			)
			(layer "F.Fab")
		)
		(fp_line
			(start 0.12065 -0.2794)
			(end 0.12065 -0.3048)
			(stroke
				(width 0.1)
				(type default)
			)
			(layer "F.Fab")
		)
		(fp_line
			(start -0.12065 -0.2794)
			(end 0.12065 -0.2794)
			(stroke
				(width 0.1)
				(type default)
			)
			(layer "F.Fab")
		)
		(fp_line
			(start 0.120396 0.2794)
			(end -0.12065 0.2794)
			(stroke
				(width 0.1)
				(type default)
			)
			(layer "F.Fab")
		)
		(fp_line
			(start -0.12065 0.2794)
			(end -0.12065 0.3048)
			(stroke
				(width 0.1)
				(type default)
			)
			(layer "F.Fab")
		)
		(fp_line
			(start 0.67945 0.3048)
			(end 0.120396 0.3048)
			(stroke
				(width 0.1)
				(type default)
			)
			(layer "F.Fab")
		)
		(fp_line
			(start 0.120396 0.3048)
			(end 0.120396 0.2794)
			(stroke
				(width 0.1)
				(type default)
			)
			(layer "F.Fab")
		)
		(fp_line
			(start -0.12065 0.3048)
			(end -0.67945 0.3048)
			(stroke
				(width 0.1)
				(type default)
			)
			(layer "F.Fab")
		)
		(fp_line
			(start -0.67945 0.3048)
			(end -0.67945 -0.305054)
			(stroke
				(width 0.1)
				(type default)
			)
			(layer "F.Fab")
		)
		(pad "1" smd circle
			(at -0.40005 0 90)
			(size 0 0)
			(layers "F.Cu" "F.Mask" "F.Paste")
			(net "OCP_SFF_PRSNT_ALL_R_N")
		)
		(pad "2" smd circle
			(at 0.40005 0 90)
			(size 0 0)
			(layers "F.Cu" "F.Mask" "F.Paste")
			(net "OCP_SFF_PRSNT_ALL_R1_N")
		)
	)
	(footprint ""
		(layer "F.Cu")
		(at 456.440794 -46.264576 -90)
		(property "Reference" "PR831"
			(at 0 0 270)
			(layer "F.SilkS")
			(hide yes)
			(effects
				(font
					(size 1.27 1.27)
				)
			)
		)
		(property "Value" ""
			(at 0 0 270)
			(layer "F.Fab")
			(effects
				(font
					(size 1.27 1.27)
				)
			)
		)
		(duplicate_pad_numbers_are_jumpers no)
		(fp_line
			(start -0.7874 0.4064)
			(end -0.7874 -0.4064)
			(stroke
				(width 0.1524)
				(type default)
			)
			(layer "F.SilkS")
		)
		(fp_line
			(start 0.7874 0.4064)
			(end -0.7874 0.4064)
			(stroke
				(width 0.1524)
				(type default)
			)
			(layer "F.SilkS")
		)
		(fp_line
			(start -0.7874 -0.4064)
			(end 0.7874 -0.4064)
			(stroke
				(width 0.1524)
				(type default)
			)
			(layer "F.SilkS")
		)
		(fp_line
			(start 0.7874 -0.4064)
			(end 0.7874 0.4064)
			(stroke
				(width 0.1524)
				(type default)
			)
			(layer "F.SilkS")
		)
		(fp_line
			(start -0.67945 0.3048)
			(end -0.67945 -0.305054)
			(stroke
				(width 0.1)
				(type default)
			)
			(layer "F.Fab")
		)
		(fp_line
			(start -0.12065 0.3048)
			(end -0.67945 0.3048)
			(stroke
				(width 0.1)
				(type default)
			)
			(layer "F.Fab")
		)
		(fp_line
			(start 0.120396 0.3048)
			(end 0.120396 0.2794)
			(stroke
				(width 0.1)
				(type default)
			)
			(layer "F.Fab")
		)
		(fp_line
			(start 0.67945 0.3048)
			(end 0.120396 0.3048)
			(stroke
				(width 0.1)
				(type default)
			)
			(layer "F.Fab")
		)
		(fp_line
			(start -0.12065 0.2794)
			(end -0.12065 0.3048)
			(stroke
				(width 0.1)
				(type default)
			)
			(layer "F.Fab")
		)
		(fp_line
			(start 0.120396 0.2794)
			(end -0.12065 0.2794)
			(stroke
				(width 0.1)
				(type default)
			)
			(layer "F.Fab")
		)
		(fp_line
			(start -0.12065 -0.2794)
			(end 0.12065 -0.2794)
			(stroke
				(width 0.1)
				(type default)
			)
			(layer "F.Fab")
		)
		(fp_line
			(start 0.12065 -0.2794)
			(end 0.12065 -0.3048)
			(stroke
				(width 0.1)
				(type default)
			)
			(layer "F.Fab")
		)
		(fp_line
			(start 0.12065 -0.3048)
			(end 0.67945 -0.3048)
			(stroke
				(width 0.1)
				(type default)
			)
			(layer "F.Fab")
		)
		(fp_line
			(start 0.67945 -0.3048)
			(end 0.67945 0.3048)
			(stroke
				(width 0.1)
				(type default)
			)
			(layer "F.Fab")
		)
		(fp_line
			(start -0.67945 -0.305054)
			(end -0.12065 -0.305054)
			(stroke
				(width 0.1)
				(type default)
			)
			(layer "F.Fab")
		)
		(fp_line
			(start -0.12065 -0.305054)
			(end -0.12065 -0.2794)
			(stroke
				(width 0.1)
				(type default)
			)
			(layer "F.Fab")
		)
		(pad "1" smd circle
			(at -0.40005 0 270)
			(size 0 0)
			(layers "F.Cu" "F.Mask" "F.Paste")
			(net "P3V3_AUX_FB")
		)
		(pad "2" smd circle
			(at 0.40005 0 270)
			(size 0 0)
			(layers "F.Cu" "F.Mask" "F.Paste")
			(net "P3V3_AUX")
		)
	)
)
